(kicad_pcb
	(version 20241229)
	(generator "pcbnew")
	(generator_version "9.0")
	(general
		(thickness 1.63)
		(legacy_teardrops no)
	)
	(paper "A4")
	(title_block
		(title "CM4 Baseboard")
		(date "2026-01-05")
		(rev "1.1.1")
		(company "Antmicro Ltd")
		(comment 1 "www.antmicro.com")
		(comment 9 "footprints 52-56 of 506")
	)
	(layers
		(0 "F.Cu" signal)
		(4 "In1.Cu" power)
		(6 "In2.Cu" power)
		(8 "In3.Cu" signal)
		(10 "In4.Cu" signal)
		(2 "B.Cu" signal)
		(9 "F.Adhes" user "F.Adhesive")
		(11 "B.Adhes" user "B.Adhesive")
		(13 "F.Paste" user)
		(15 "B.Paste" user)
		(5 "F.SilkS" user "F.Silkscreen")
		(7 "B.SilkS" user "B.Silkscreen")
		(1 "F.Mask" user)
		(3 "B.Mask" user)
		(17 "Dwgs.User" user "User.Drawings")
		(19 "Cmts.User" user "User.Comments")
		(21 "Eco1.User" user "User.Eco1")
		(23 "Eco2.User" user "User.Eco2")
		(25 "Edge.Cuts" user)
		(27 "Margin" user)
		(31 "F.CrtYd" user "F.Courtyard")
		(29 "B.CrtYd" user "B.Courtyard")
		(35 "F.Fab" user)
		(33 "B.Fab" user)
	)
	(footprint "antmicro-footprints:R_0402_1005Metric"
		(layer "F.Cu")
		(at 66.925 168.3 180)
		(descr "Resistor SMD 0402")
		(tags "resistor SMD 0402")
		(property "Reference" "R4"
			(at 0.8 0.425 0)
			(layer "F.SilkS")
			(effects
				(font
					(size 0.7 0.7)
					(thickness 0.15)
				)
				(justify right top)
			)
		)
		(property "Value" "R_0R_0402"
			(at -1.011843 1.772047 0)
			(layer "F.Fab")
			(effects
				(font
					(size 0.7 0.7)
					(thickness 0.15)
				)
				(justify right top)
			)
		)
		(property "Datasheet" "https://industrial.panasonic.com/cdbs/www-data/pdf/RDA0000/AOA0000C301.pdf"
			(at 0 0 0)
			(layer "F.Fab")
			(hide yes)
			(effects
				(font
					(size 1.27 1.27)
					(thickness 0.15)
				)
			)
		)
		(property "Description" "SMD Chip Resistor, Jumper, 0 ohm, 100 mW, 0402 [1005 Metric], Thick Film, General Purpose"
			(at 0 0 0)
			(layer "F.Fab")
			(hide yes)
			(effects
				(font
					(size 1.27 1.27)
					(thickness 0.15)
				)
			)
		)
		(property "MPN" "ERJ2GE0R00X"
			(at 0 0 180)
			(unlocked yes)
			(layer "F.Fab")
			(hide yes)
			(effects
				(font
					(size 1 1)
					(thickness 0.15)
				)
			)
		)
		(property "Manufacturer" "Panasonic"
			(at 0 0 180)
			(unlocked yes)
			(layer "F.Fab")
			(hide yes)
			(effects
				(font
					(size 1 1)
					(thickness 0.15)
				)
			)
		)
		(property "License" "Apache-2.0"
			(at 0 0 180)
			(unlocked yes)
			(layer "F.Fab")
			(hide yes)
			(effects
				(font
					(size 1 1)
					(thickness 0.15)
				)
			)
		)
		(property "Author" "Antmicro"
			(at 0 0 180)
			(unlocked yes)
			(layer "F.Fab")
			(hide yes)
			(effects
				(font
					(size 1 1)
					(thickness 0.15)
				)
			)
		)
		(property "Val" "0R"
			(at 0 0 180)
			(unlocked yes)
			(layer "F.Fab")
			(hide yes)
			(effects
				(font
					(size 1 1)
					(thickness 0.15)
				)
			)
		)
		(property "Tolerance" "~"
			(at 0 0 180)
			(unlocked yes)
			(layer "F.Fab")
			(hide yes)
			(effects
				(font
					(size 1 1)
					(thickness 0.15)
				)
			)
		)
		(property "Current" "1A"
			(at 0 0 180)
			(unlocked yes)
			(layer "F.Fab")
			(hide yes)
			(effects
				(font
					(size 1 1)
					(thickness 0.15)
				)
			)
		)
		(sheetname "/Peripherals/")
		(sheetfile "peripherals.kicad_sch")
		(attr smd exclude_from_pos_files exclude_from_bom dnp)
		(fp_rect
			(start -0.925 -0.47)
			(end 0.925 0.47)
			(stroke
				(width 0.05)
				(type default)
			)
			(fill no)
			(layer "F.CrtYd")
		)
		(fp_rect
			(start -0.5 -0.25)
			(end 0.5 0.25)
			(stroke
				(width 0.15)
				(type solid)
			)
			(fill no)
			(layer "F.Fab")
		)
		(fp_text user "Author: Antmicro"
			(at -0.95 4.169 0)
			(layer "F.Fab")
			(effects
				(font
					(size 0.7 0.7)
					(thickness 0.15)
				)
				(justify right top)
			)
		)
		(fp_text user "License: Apache-2.0"
			(at -0.95 5.169 0)
			(layer "F.Fab")
			(effects
				(font
					(size 0.7 0.7)
					(thickness 0.15)
				)
				(justify right top)
			)
		)
		(fp_text user "${REFERENCE}"
			(at -0.95 3.168 0)
			(layer "F.Fab")
			(effects
				(font
					(size 0.7 0.7)
					(thickness 0.15)
				)
				(justify right top)
			)
		)
		(pad "1" smd roundrect
			(at -0.48 0 180)
			(size 0.59 0.64)
			(layers "F.Cu" "F.Mask" "F.Paste")
			(roundrect_rratio 0.25)
			(net 501 "Net-(U801-V_{DD(UP)})")
			(pintype "passive")
		)
		(pad "2" smd roundrect
			(at 0.48 0 180)
			(size 0.59 0.64)
			(layers "F.Cu" "F.Mask" "F.Paste")
			(roundrect_rratio 0.25)
			(net 9 "+3V3")
			(pintype "passive")
		)
	)
	(footprint "antmicro-footprints:FB_0402_1005Metric"
		(layer "F.Cu")
		(at 90.192962 130.0515 -90)
		(descr "Ferrite Bead SMD 0402")
		(tags "ferrite bead SMD 0402")
		(property "Reference" "FB903"
			(at -0.99 -1.315 90)
			(layer "F.SilkS")
			(effects
				(font
					(size 0.7 0.7)
					(thickness 0.15)
				)
				(justify right bottom)
			)
		)
		(property "Value" "FB_120Z_1.3A_Murata-BLM15PD_0402"
			(at 0 1.4 90)
			(layer "F.Fab")
			(effects
				(font
					(size 0.7 0.7)
					(thickness 0.15)
				)
				(justify right bottom)
			)
		)
		(property "Datasheet" "https://www.murata.com/en-us/products/productdata/8796740059166/ENFA0018.pdf"
			(at 0 0 270)
			(layer "F.Fab")
			(hide yes)
			(effects
				(font
					(size 1.27 1.27)
					(thickness 0.15)
				)
			)
		)
		(property "MPN" "BLM15PD121SN1D"
			(at 0 0 270)
			(unlocked yes)
			(layer "F.Fab")
			(hide yes)
			(effects
				(font
					(size 1 1)
					(thickness 0.15)
				)
			)
		)
		(property "Manufacturer" "Murata"
			(at 0 0 270)
			(unlocked yes)
			(layer "F.Fab")
			(hide yes)
			(effects
				(font
					(size 1 1)
					(thickness 0.15)
				)
			)
		)
		(property "Author" "Antmicro"
			(at 0 0 270)
			(unlocked yes)
			(layer "F.Fab")
			(hide yes)
			(effects
				(font
					(size 1 1)
					(thickness 0.15)
				)
			)
		)
		(property "License" "Apache-2.0"
			(at 0 0 270)
			(unlocked yes)
			(layer "F.Fab")
			(hide yes)
			(effects
				(font
					(size 1 1)
					(thickness 0.15)
				)
			)
		)
		(property "Val" "120Z/1.3A"
			(at 0 0 270)
			(unlocked yes)
			(layer "F.Fab")
			(hide yes)
			(effects
				(font
					(size 1 1)
					(thickness 0.15)
				)
			)
		)
		(property "Current" ""
			(at 0 0 270)
			(unlocked yes)
			(layer "F.Fab")
			(hide yes)
			(effects
				(font
					(size 1 1)
					(thickness 0.15)
				)
			)
		)
		(sheetname "/USB/")
		(sheetfile "usb.kicad_sch")
		(attr smd)
		(fp_rect
			(start -0.925 -0.47)
			(end 0.925 0.47)
			(stroke
				(width 0.05)
				(type default)
			)
			(fill no)
			(layer "F.CrtYd")
		)
		(fp_rect
			(start -0.5 -0.25)
			(end 0.5 0.25)
			(stroke
				(width 0.15)
				(type solid)
			)
			(fill no)
			(layer "F.Fab")
		)
		(fp_text user "License: Apache-2.0"
			(at -0.95 5.169 270)
			(layer "F.Fab")
			(effects
				(font
					(size 0.7 0.7)
					(thickness 0.15)
				)
				(justify left bottom)
			)
		)
		(fp_text user "${REFERENCE}"
			(at -0.95 3.168 270)
			(layer "F.Fab")
			(effects
				(font
					(size 0.7 0.7)
					(thickness 0.15)
				)
				(justify left bottom)
			)
		)
		(fp_text user "Author: Antmicro"
			(at -0.95 4.169 270)
			(layer "F.Fab")
			(effects
				(font
					(size 0.7 0.7)
					(thickness 0.15)
				)
				(justify left bottom)
			)
		)
		(pad "1" smd roundrect
			(at -0.48 0 270)
			(size 0.59 0.64)
			(layers "F.Cu" "F.Mask" "F.Paste")
			(roundrect_rratio 0.25)
			(net 471 "Net-(D910-C)")
			(pintype "passive")
		)
		(pad "2" smd roundrect
			(at 0.48 0 270)
			(size 0.59 0.64)
			(layers "F.Cu" "F.Mask" "F.Paste")
			(roundrect_rratio 0.25)
			(net 211 "/USB/VCC_PD")
			(pintype "passive")
		)
	)
	(footprint "antmicro-footprints:TP_SMD_0.75mm"
		(layer "F.Cu")
		(at 94.45 131.55)
		(property "Reference" "TP918"
			(at 2.45 2.96 0)
			(layer "F.SilkS")
			(effects
				(font
					(size 0.7 0.7)
					(thickness 0.15)
				)
				(justify left bottom)
			)
		)
		(property "Value" "TP_0.75mm_SMD"
			(at 0 1.2 0)
			(layer "F.Fab")
			(effects
				(font
					(size 0.7 0.7)
					(thickness 0.15)
				)
				(justify left bottom)
			)
		)
		(property "MPN" ""
			(at 0 0 0)
			(unlocked yes)
			(layer "F.Fab")
			(hide yes)
			(effects
				(font
					(size 1 1)
					(thickness 0.15)
				)
			)
		)
		(property "Manufacturer" ""
			(at 0 0 0)
			(unlocked yes)
			(layer "F.Fab")
			(hide yes)
			(effects
				(font
					(size 1 1)
					(thickness 0.15)
				)
			)
		)
		(property "Author" "Antmicro"
			(at 0 0 0)
			(unlocked yes)
			(layer "F.Fab")
			(hide yes)
			(effects
				(font
					(size 1 1)
					(thickness 0.15)
				)
			)
		)
		(property "License" "Apache-2.0"
			(at 0 0 0)
			(unlocked yes)
			(layer "F.Fab")
			(hide yes)
			(effects
				(font
					(size 1 1)
					(thickness 0.15)
				)
			)
		)
		(sheetname "/USB/")
		(sheetfile "usb.kicad_sch")
		(attr exclude_from_pos_files exclude_from_bom)
		(fp_circle
			(center 0 0)
			(end 0.475 0)
			(stroke
				(width 0.05)
				(type default)
			)
			(fill no)
			(layer "F.CrtYd")
		)
		(fp_text user "${REFERENCE}"
			(at -0.4 2.7 0)
			(layer "F.Fab")
			(effects
				(font
					(size 0.7 0.7)
					(thickness 0.15)
				)
				(justify left bottom)
			)
		)
		(fp_text user "Author: Antmicro"
			(at -0.4 3.901 0)
			(layer "F.Fab")
			(effects
				(font
					(size 0.7 0.7)
					(thickness 0.15)
				)
				(justify left bottom)
			)
		)
		(fp_text user "License: Apache-2.0"
			(at -0.4 5.101 0)
			(layer "F.Fab")
			(effects
				(font
					(size 0.7 0.7)
					(thickness 0.15)
				)
				(justify left bottom)
			)
		)
		(pad "1" smd circle
			(at 0 0)
			(size 0.75 0.75)
			(layers "F.Cu" "F.Mask")
			(net 449 "Net-(U905-GPIO1)")
			(pinfunction "1")
			(pintype "passive")
		)
	)
	(footprint "antmicro-footprints:C_Pol_EIA-B"
		(layer "F.Cu")
		(at 101.777962 126.063)
		(property "Reference" "C929"
			(at 1.94 1.8135 0)
			(layer "F.SilkS")
			(effects
				(font
					(size 0.7 0.7)
					(thickness 0.15)
				)
				(justify left bottom)
			)
		)
		(property "Value" "C_Pol_330u_6.3V_KEMET-T520-B"
			(at 0 2.85 0)
			(layer "F.Fab")
			(effects
				(font
					(size 0.7 0.7)
					(thickness 0.15)
				)
				(justify left bottom)
			)
		)
		(property "Datasheet" "https://www.kemet.com/en/us/capacitors/product/T520B337M006ATE040.html"
			(at 0 0 0)
			(layer "F.Fab")
			(hide yes)
			(effects
				(font
					(size 1.27 1.27)
					(thickness 0.15)
				)
			)
		)
		(property "Val" "330u"
			(at 0 0 0)
			(unlocked yes)
			(layer "F.Fab")
			(hide yes)
			(effects
				(font
					(size 1 1)
					(thickness 0.15)
				)
			)
		)
		(property "MPN" "T520B337M006ATE040"
			(at 0 0 0)
			(unlocked yes)
			(layer "F.Fab")
			(hide yes)
			(effects
				(font
					(size 1 1)
					(thickness 0.15)
				)
			)
		)
		(property "Manufacturer" "KEMET"
			(at 0 0 0)
			(unlocked yes)
			(layer "F.Fab")
			(hide yes)
			(effects
				(font
					(size 1 1)
					(thickness 0.15)
				)
			)
		)
		(property "License" "Apache-2.0"
			(at 0 0 0)
			(unlocked yes)
			(layer "F.Fab")
			(hide yes)
			(effects
				(font
					(size 1 1)
					(thickness 0.15)
				)
			)
		)
		(property "Author" "Antmicro"
			(at 0 0 0)
			(unlocked yes)
			(layer "F.Fab")
			(hide yes)
			(effects
				(font
					(size 1 1)
					(thickness 0.15)
				)
			)
		)
		(property "Voltage" "6.3V"
			(at 0 0 0)
			(unlocked yes)
			(layer "F.Fab")
			(hide yes)
			(effects
				(font
					(size 1 1)
					(thickness 0.15)
				)
			)
		)
		(property "Dielectric" "template_dielectric"
			(at 0 0 0)
			(unlocked yes)
			(layer "F.Fab")
			(hide yes)
			(effects
				(font
					(size 1 1)
					(thickness 0.15)
				)
			)
		)
		(sheetname "/USB/")
		(sheetfile "usb.kicad_sch")
		(attr smd)
		(fp_line
			(start -2.521 -1.676)
			(end -2.123 -1.676)
			(stroke
				(width 0.15)
				(type solid)
			)
			(layer "F.SilkS")
		)
		(fp_line
			(start -2.325 -1.475)
			(end -2.325 -1.878)
			(stroke
				(width 0.15)
				(type solid)
			)
			(layer "F.SilkS")
		)
		(fp_line
			(start -1.8 -1.6)
			(end 1.8 -1.6)
			(stroke
				(width 0.15)
				(type solid)
			)
			(layer "F.SilkS")
		)
		(fp_line
			(start -1.8 -1.3)
			(end -1.8 -1.6)
			(stroke
				(width 0.15)
				(type solid)
			)
			(layer "F.SilkS")
		)
		(fp_line
			(start -1.8 1.3)
			(end -1.8 1.6)
			(stroke
				(width 0.15)
				(type solid)
			)
			(layer "F.SilkS")
		)
		(fp_line
			(start 1.8 -1.3)
			(end 1.8 -1.6)
			(stroke
				(width 0.15)
				(type solid)
			)
			(layer "F.SilkS")
		)
		(fp_line
			(start 1.8 1.3)
			(end 1.8 1.6)
			(stroke
				(width 0.15)
				(type solid)
			)
			(layer "F.SilkS")
		)
		(fp_line
			(start 1.8 1.6)
			(end -1.8 1.6)
			(stroke
				(width 0.15)
				(type solid)
			)
			(layer "F.SilkS")
		)
		(fp_line
			(start -2.411 -1.35)
			(end -2.41 1.35)
			(stroke
				(width 0.05)
				(type solid)
			)
			(layer "F.CrtYd")
		)
		(fp_line
			(start -1.97 -1.75)
			(end -1.97 -1.35)
			(stroke
				(width 0.05)
				(type solid)
			)
			(layer "F.CrtYd")
		)
		(fp_line
			(start -1.97 -1.35)
			(end -2.41 -1.35)
			(stroke
				(width 0.05)
				(type solid)
			)
			(layer "F.CrtYd")
		)
		(fp_line
			(start -1.97 1.35)
			(end -2.41 1.35)
			(stroke
				(width 0.05)
				(type solid)
			)
			(layer "F.CrtYd")
		)
		(fp_line
			(start -1.97 1.35)
			(end -1.97 1.75)
			(stroke
				(width 0.05)
				(type solid)
			)
			(layer "F.CrtYd")
		)
		(fp_line
			(start 1.959 -1.75)
			(end -1.97 -1.75)
			(stroke
				(width 0.05)
				(type solid)
			)
			(layer "F.CrtYd")
		)
		(fp_line
			(start 1.959 -1.75)
			(end 1.959 -1.35)
			(stroke
				(width 0.05)
				(type solid)
			)
			(layer "F.CrtYd")
		)
		(fp_line
			(start 1.96 1.35)
			(end 1.96 1.75)
			(stroke
				(width 0.05)
				(type solid)
			)
			(layer "F.CrtYd")
		)
		(fp_line
			(start 1.96 1.75)
			(end -1.97 1.75)
			(stroke
				(width 0.05)
				(type solid)
			)
			(layer "F.CrtYd")
		)
		(fp_line
			(start 2.399 -1.35)
			(end 1.959 -1.35)
			(stroke
				(width 0.05)
				(type solid)
			)
			(layer "F.CrtYd")
		)
		(fp_line
			(start 2.399 -1.35)
			(end 2.4 1.35)
			(stroke
				(width 0.05)
				(type solid)
			)
			(layer "F.CrtYd")
		)
		(fp_line
			(start 2.4 1.35)
			(end 1.96 1.35)
			(stroke
				(width 0.05)
				(type solid)
			)
			(layer "F.CrtYd")
		)
		(fp_line
			(start -1.7 1.324)
			(end -1.551 1.475)
			(stroke
				(width 0.15)
				(type solid)
			)
			(layer "F.Fab")
		)
		(fp_rect
			(start -1.72 -1.5)
			(end 1.719 1.499)
			(stroke
				(width 0.15)
				(type solid)
			)
			(fill no)
			(layer "F.Fab")
		)
		(fp_text user "License: Apache-2.0"
			(at -2.665 5.65 0)
			(layer "F.Fab")
			(effects
				(font
					(size 0.7 0.7)
					(thickness 0.15)
				)
				(justify left bottom)
			)
		)
		(fp_text user "Author: Antmicro"
			(at -2.665 6.85 0)
			(layer "F.Fab")
			(effects
				(font
					(size 0.7 0.7)
					(thickness 0.15)
				)
				(justify left bottom)
			)
		)
		(fp_text user "${REFERENCE}"
			(at -2.665 4.45 0)
			(layer "F.Fab")
			(effects
				(font
					(size 0.7 0.7)
					(thickness 0.15)
				)
				(justify left bottom)
			)
		)
		(pad "1" smd roundrect
			(at -1.551 0)
			(size 1.2 2.2)
			(layers "F.Cu" "F.Mask" "F.Paste")
			(roundrect_rratio 0.1)
			(net 28 "/USB/+5V_{CAP}")
			(pintype "passive")
		)
		(pad "2" smd roundrect
			(at 1.55 0)
			(size 1.2 2.2)
			(layers "F.Cu" "F.Mask" "F.Paste")
			(roundrect_rratio 0.1)
			(net 3 "GND")
			(pintype "passive")
		)
	)
	(footprint "antmicro-footprints:SOD-523"
		(layer "F.Cu")
		(at 96.107962 120.6165)
		(property "Reference" "D903"
			(at 24.645 26.035 0)
			(layer "F.SilkS")
			(effects
				(font
					(size 0.7 0.7)
					(thickness 0.15)
				)
				(justify left bottom)
			)
		)
		(property "Value" "PESD5Z5_0F"
			(at 0 1.499 0)
			(layer "F.Fab")
			(effects
				(font
					(size 0.7 0.7)
					(thickness 0.15)
				)
				(justify left bottom)
			)
		)
		(property "Datasheet" "https://assets.nexperia.com/documents/data-sheet/PESD5Z5_0.pdf"
			(at 0 0 0)
			(layer "F.Fab")
			(hide yes)
			(effects
				(font
					(size 1.27 1.27)
					(thickness 0.15)
				)
			)
		)
		(property "Manufacturer" "Nexperia"
			(at 0 0 0)
			(unlocked yes)
			(layer "F.Fab")
			(hide yes)
			(effects
				(font
					(size 1 1)
					(thickness 0.15)
				)
			)
		)
		(property "MPN" "PESD5Z5.0F"
			(at 0 0 0)
			(unlocked yes)
			(layer "F.Fab")
			(hide yes)
			(effects
				(font
					(size 1 1)
					(thickness 0.15)
				)
			)
		)
		(property "Author" "Antmicro"
			(at 0 0 0)
			(unlocked yes)
			(layer "F.Fab")
			(hide yes)
			(effects
				(font
					(size 1 1)
					(thickness 0.15)
				)
			)
		)
		(property "License" "Apache-2.0"
			(at 0 0 0)
			(unlocked yes)
			(layer "F.Fab")
			(hide yes)
			(effects
				(font
					(size 1 1)
					(thickness 0.15)
				)
			)
		)
		(sheetname "/USB/")
		(sheetfile "usb.kicad_sch")
		(attr smd)
		(fp_line
			(start -0.35 -0.5)
			(end -0.35 0.5)
			(stroke
				(width 0.15)
				(type solid)
			)
			(layer "F.SilkS")
		)
		(fp_rect
			(start -1 -0.6)
			(end 1 0.6)
			(stroke
				(width 0.05)
				(type solid)
			)
			(fill no)
			(layer "F.CrtYd")
		)
		(fp_line
			(start -0.652 -0.425)
			(end 0.65 -0.425)
			(stroke
				(width 0.15)
				(type solid)
			)
			(layer "F.Fab")
		)
		(fp_line
			(start -0.652 0.423)
			(end -0.652 -0.425)
			(stroke
				(width 0.15)
				(type solid)
			)
			(layer "F.Fab")
		)
		(fp_line
			(start -0.652 0.423)
			(end 0.65 0.423)
			(stroke
				(width 0.15)
				(type solid)
			)
			(layer "F.Fab")
		)
		(fp_line
			(start -0.35 -0.4)
			(end -0.35 0.4)
			(stroke
				(width 0.15)
				(type solid)
			)
			(layer "F.Fab")
		)
		(fp_line
			(start 0.65 -0.425)
			(end 0.65 0.423)
			(stroke
				(width 0.15)
				(type solid)
			)
			(layer "F.Fab")
		)
		(fp_text user "Author: Antmicro"
			(at -1.276 4.7 0)
			(layer "F.Fab")
			(effects
				(font
					(size 0.7 0.7)
					(thickness 0.15)
				)
				(justify left bottom)
			)
		)
		(fp_text user "License: Apache-2.0"
			(at -1.276 5.9 0)
			(layer "F.Fab")
			(effects
				(font
					(size 0.7 0.7)
					(thickness 0.15)
				)
				(justify left bottom)
			)
		)
		(fp_text user "${REFERENCE}"
			(at -1.276 3.499 0)
			(layer "F.Fab")
			(effects
				(font
					(size 0.7 0.7)
					(thickness 0.15)
				)
				(justify left bottom)
			)
		)
		(pad "1" smd roundrect
			(at -0.701 0)
			(size 0.5 0.6)
			(layers "F.Cu" "F.Mask" "F.Paste")
			(roundrect_rratio 0.25)
			(net 24 "/Compute module/USBA_VBUS")
			(pinfunction "C")
			(pintype "passive")
		)
		(pad "2" smd roundrect
			(at 0.699 0)
			(size 0.5 0.6)
			(layers "F.Cu" "F.Mask" "F.Paste")
			(roundrect_rratio 0.25)
			(net 3 "GND")
			(pinfunction "A")
			(pintype "passive")
		)
	)
)
